# S9S_MB_2U (Grand Teton) — schematic netlist excerpt (pin names and nets, part order shuffled) for the footprints in the layout excerpt that follows; sources: Cadence DE-HDL packaged netlist, KiCad conversion of 03242023_DA0F0TMBIJ0_F0T_Motherboard_J_brd_V01_OCP.brd

J1  SCONN288_ADR50017P130CC  SCONN288_ADR50017-P130CC IO  pkg DDR288S_1-1VXB  page 82
  VIN_BULK0  = P12V_S3_AUX_CPU0_NVDIMM
  RFU0  = TP_CHA_CPU0_DIMM1_FRU_0
  VIN_MGMT  = P3V3_AUX
  HSCL  = I3C_SPD_DDRABCD_CPU0_LVC1_SCL_R
  HSDA  = I3C_SPD_DDRABCD_CPU0_LVC1_SDA
  VSS0  = GND
  DQ0_A  = M_A_CPU0_SA_DQ<0>
  VSS1  = GND
  DQ1_A  = M_A_CPU0_SA_DQ<1>
  VSS2  = GND
  DQS0_A_T  = M_A_CPU0_SA_DQS_DP<0>
  DQS0_A_C  = M_A_CPU0_SA_DQS_DN<0>
  VSS3  = GND
  DQ4_A  = M_A_CPU0_SA_DQ<4>
  VSS4  = GND
  DQ5_A  = M_A_CPU0_SA_DQ<5>
  VSS5  = GND
  DQ8_A  = M_A_CPU0_SA_DQ<8>
  VSS6  = GND
  DQ9_A  = M_A_CPU0_SA_DQ<9>
  VSS7  = GND
  DQS1_A_T  = M_A_CPU0_SA_DQS_DP<1>
  DQS1_A_C  = M_A_CPU0_SA_DQS_DN<1>
  VSS8  = GND
  DQ12_A  = M_A_CPU0_SA_DQ<12>
  VSS9  = GND
  DQ13_A  = M_A_CPU0_SA_DQ<13>
  VSS10  = GND
  DQ16_A  = M_A_CPU0_SA_DQ<16>
  VSS11  = GND
  DQ17_A  = M_A_CPU0_SA_DQ<17>
  VSS12  = GND
  DQS2_A_T  = M_A_CPU0_SA_DQS_DP<2>
  DQS2_A_C  = M_A_CPU0_SA_DQS_DN<2>
  VSS13  = GND
  DQ20_A  = M_A_CPU0_SA_DQ<20>
  VSS14  = GND
  DQ21_A  = M_A_CPU0_SA_DQ<21>
  VSS15  = GND
  DQ24_A  = M_A_CPU0_SA_DQ<24>
  VSS16  = GND
  DQ25_A  = M_A_CPU0_SA_DQ<25>
  VSS17  = GND
  DQS3_A_T  = M_A_CPU0_SA_DQS_DP<3>
  DQS3_A_C  = M_A_CPU0_SA_DQS_DN<3>
  VSS18  = GND
  DQ28_A  = M_A_CPU0_SA_DQ<28>
  VSS19  = GND
  DQ29_A  = M_A_CPU0_SA_DQ<29>
  VSS20  = GND
  CB0_A  = M_A_CPU0_SA_CB<0>
  VSS21  = GND
  CB1_A  = M_A_CPU0_SA_CB<1>
  VSS22  = GND
  DQS4_A_T  = M_A_CPU0_SA_DQS_DP<4>
  DQS4_A_C  = M_A_CPU0_SA_DQS_DN<4>
  VSS23  = GND
  CB4_A  = M_A_CPU0_SA_CB<4>
  VSS24  = GND
  CB5_A  = M_A_CPU0_SA_CB<5>
  VSS25  = GND
  ALERT_N  = M_A_CPU0_ALERT_N
  VSS26  = GND
  CS0_A_N  = M_A_CPU0_SA_CS_N<0>
  VSS27  = GND
  CA0_A  = M_A_CPU0_SA_CA<0>
  VSS28  = GND
  CA2_A  = M_A_CPU0_SA_CA<2>
  VSS29  = GND
  CA4_A  = M_A_CPU0_SA_CA<4>
  VSS30  = GND
  CA6_A  = M_A_CPU0_SA_CA<6>
  VSS31  = GND
  PAR_A  = M_A_CPU0_SA_PAR
  VSS32  = GND
  CA0_B  = M_A_CPU0_SB_CA<0>
  VSS33  = GND
  CA2_B  = M_A_CPU0_SB_CA<2>
  VSS34  = GND
  CA4_B  = M_A_CPU0_SB_CA<4>
  VSS35  = GND
  CA6_B  = M_A_CPU0_SB_CA<6>
  VSS36  = GND
  CS0_B_N  = M_A_CPU0_SB_CS_N<0>
  VSS37  = GND
  \lbd||rsp_a_n\  = M_A_CPU0_SA_RSP<0>
  \lbs||rsp_b_n\  = M_A_CPU0_SB_RSP<0>
  VSS38  = GND
  CB4_B  = M_A_CPU0_SB_CB<4>
  VSS39  = GND
  CB5_B  = M_A_CPU0_SB_CB<5>
  VSS40  = GND
  \dqs9_b_t||tdqs9_b_t||dbi4_b_n\  = M_A_CPU0_SB_DQS_DP<9>
  \dqs9_b_c||tdqs9_b_c\  = M_A_CPU0_SB_DQS_DN<9>
  VSS41  = GND
  CB0_B  = M_A_CPU0_SB_CB<0>
  VSS42  = GND
  CB1_B  = M_A_CPU0_SB_CB<1>
  VSS43  = GND
  DQ0_B  = M_A_CPU0_SB_DQ<0>
  VSS44  = GND
  DQ1_B  = M_A_CPU0_SB_DQ<1>
  VSS45  = GND
  DQS0_B_T  = M_A_CPU0_SB_DQS_DP<0>
  DQS0_B_C  = M_A_CPU0_SB_DQS_DN<0>
  VSS46  = GND
  DQ4_B  = M_A_CPU0_SB_DQ<4>
  VSS47  = GND
  DQ5_B  = M_A_CPU0_SB_DQ<5>
  VSS48  = GND
  DQ8_B  = M_A_CPU0_SB_DQ<8>
  VSS49  = GND
  DQ9_B  = M_A_CPU0_SB_DQ<9>
  VSS50  = GND
  DQS1_B_T  = M_A_CPU0_SB_DQS_DP<1>
  DQS1_B_C  = M_A_CPU0_SB_DQS_DN<1>
  VSS51  = GND
  DQ12_B  = M_A_CPU0_SB_DQ<12>
  VSS52  = GND
  DQ13_B  = M_A_CPU0_SB_DQ<13>
  VSS53  = GND
  DQ16_B  = M_A_CPU0_SB_DQ<16>
  VSS54  = GND
  DQ17_B  = M_A_CPU0_SB_DQ<17>
  VSS55  = GND
  DQS2_B_T  = M_A_CPU0_SB_DQS_DP<2>
  DQS2_B_C  = M_A_CPU0_SB_DQS_DN<2>
  VSS56  = GND
  DQ20_B  = M_A_CPU0_SB_DQ<20>
  VSS57  = GND
  DQ21_B  = M_A_CPU0_SB_DQ<21>
  VSS58  = GND
  DQ24_B  = M_A_CPU0_SB_DQ<24>
  VSS59  = GND
  DQ25_B  = M_A_CPU0_SB_DQ<25>
  VSS60  = GND
  DQS3_B_T  = M_A_CPU0_SB_DQS_DP<3>
  DQS3_B_C  = M_A_CPU0_SB_DQS_DN<3>
  VSS61  = GND
  DQ28_B  = M_A_CPU0_SB_DQ<28>
  VSS62  = GND
  DQ29_B  = M_A_CPU0_SB_DQ<29>
  VSS63  = GND
  RFU1  = TP_CHA_CPU0_DIMM1_FRU_1
  VIN_BULK1  = P12V_S3_AUX_CPU0_NVDIMM
  VIN_BULK2  = P12V_S3_AUX_CPU0_NVDIMM
  \pwr_good||fail_n\  = PWRGD_CHA_CPU0_DIMM1
  HSA  = PD_CHA_CPU0_DIMM1_SAA
  RFU2  = TP_CHA_CPU0_DIMM1_FRU_2
  RFU3  = TP_CHA_CPU0_DIMM1_FRU_3
  VSS64  = GND
  DQ2_A  = M_A_CPU0_SA_DQ<2>
  VSS65  = GND
  DQ3_A  = M_A_CPU0_SA_DQ<3>
  VSS66  = GND
  \dqs5_a_c||tdqs5_a_c||dqs5_a_t||tdqs5_a_t\  = M_A_CPU0_SA_DQS_DN<5>
  \dqs5_a_t||tdqs5_a_t\  = M_A_CPU0_SA_DQS_DP<5>
  VSS67  = GND
  DQ6_A  = M_A_CPU0_SA_DQ<6>
  VSS68  = GND
  DQ7_A  = M_A_CPU0_SA_DQ<7>
  VSS69  = GND
  DQ10_A  = M_A_CPU0_SA_DQ<10>
  VSS70  = GND
  DQ11_A  = M_A_CPU0_SA_DQ<11>
  VSS71  = GND
  \dqs6_a_c||tdqs6_a_c||dqs6_a_t||tdqs6_a_t\  = M_A_CPU0_SA_DQS_DN<6>
  \dqs6_a_t||tdqs6_a_t\  = M_A_CPU0_SA_DQS_DP<6>
  VSS72  = GND
  DQ14_A  = M_A_CPU0_SA_DQ<14>
  VSS73  = GND
  DQ15_A  = M_A_CPU0_SA_DQ<15>
  VSS74  = GND
  DQ18_A  = M_A_CPU0_SA_DQ<18>
  VSS75  = GND
  DQ19_A  = M_A_CPU0_SA_DQ<19>
  VSS76  = GND
  \dqs7_a_c||tdqs7_a_c\  = M_A_CPU0_SA_DQS_DN<7>
  \dqs7_a_t||tdqs7_a_t\  = M_A_CPU0_SA_DQS_DP<7>
  VSS77  = GND
  DQ22_A  = M_A_CPU0_SA_DQ<22>
  VSS78  = GND
  DQ23_A  = M_A_CPU0_SA_DQ<23>
  VSS79  = GND
  DQ26_A  = M_A_CPU0_SA_DQ<26>
  VSS80  = GND
  DQ27_A  = M_A_CPU0_SA_DQ<27>
  VSS81  = GND
  \dqs8_a_c||tdqs8_a_c\  = M_A_CPU0_SA_DQS_DN<8>
  \dqs8_a_t||tdqs8_a_t\  = M_A_CPU0_SA_DQS_DP<8>
  VSS82  = GND
  DQ30_A  = M_A_CPU0_SA_DQ<30>
  VSS83  = GND
  DQ31_A  = M_A_CPU0_SA_DQ<31>
  VSS84  = GND
  CB2_A  = M_A_CPU0_SA_CB<2>
  VSS85  = GND
  CB3_A  = M_A_CPU0_SA_CB<3>
  VSS86  = GND
  \dqs9_a_c||tdqs9_a_c\  = M_A_CPU0_SA_DQS_DN<9>
  \dqs9_a_t||tdqs9_a_t\  = M_A_CPU0_SA_DQS_DP<9>
  VSS87  = GND
  CB6_A  = M_A_CPU0_SA_CB<6>
  VSS88  = GND
  CB7_A  = M_A_CPU0_SA_CB<7>
  VSS89  = GND
  RESET_N  = RST_M_AB_CPU0_FPGA_N
  VSS90  = GND
  CS1_A_N  = M_A_CPU0_SA_CS_N<1>
  VSS91  = GND
  CA1_A  = M_A_CPU0_SA_CA<1>
  VSS92  = GND
  CA3_A  = M_A_CPU0_SA_CA<3>
  VSS93  = GND
  CA5_A  = M_A_CPU0_SA_CA<5>
  VSS94  = GND
  CK_T  = M_A_CPU0_CLK_DP<0>
  CK_C  = M_A_CPU0_CLK_DN<0>
  VSS95  = GND
  RFU4  = TP_CHA_CPU0_DIMM1_FRU_4
  CA1_B  = M_A_CPU0_SB_CA<1>
  VSS96  = GND
  CA3_B  = M_A_CPU0_SB_CA<3>
  VSS97  = GND
  CA5_B  = M_A_CPU0_SB_CA<5>
  VSS98  = GND
  PAR_B  = M_A_CPU0_SB_PAR
  VSS99  = GND
  CS1_B_N  = M_A_CPU0_SB_CS_N<1>
  VSS100  = GND
  RFU5  = TP_CHA_CPU0_DIMM1_FRU_5
  RFU6  = TP_CHA_CPU0_DIMM1_FRU_6
  VSS101  = GND
  CB6_B  = M_A_CPU0_SB_CB<6>
  VSS102  = GND
  CB7_B  = M_A_CPU0_SB_CB<7>
  VSS103  = GND
  DQS4_B_C  = M_A_CPU0_SB_DQS_DN<4>
  DQS4_B_T  = M_A_CPU0_SB_DQS_DP<4>
  VSS104  = GND
  CB2_B  = M_A_CPU0_SB_CB<2>
  VSS105  = GND
  CB3_B  = M_A_CPU0_SB_CB<3>
  VSS106  = GND
  DQ2_B  = M_A_CPU0_SB_DQ<2>
  VSS107  = GND
  DQ3_B  = M_A_CPU0_SB_DQ<3>
  VSS108  = GND
  \dqs5_b_c||tdqs5_b_c\  = M_A_CPU0_SB_DQS_DN<5>
  \dqs5_b_t||tdqs5_b_t\  = M_A_CPU0_SB_DQS_DP<5>
  VSS109  = GND
  DQ6_B  = M_A_CPU0_SB_DQ<6>
  VSS110  = GND
  DQ7_B  = M_A_CPU0_SB_DQ<7>
  VSS111  = GND
  DQ10_B  = M_A_CPU0_SB_DQ<10>
  VSS112  = GND
  DQ11_B  = M_A_CPU0_SB_DQ<11>
  VSS113  = GND
  \dqs6_b_c||tdqs6_b_c\  = M_A_CPU0_SB_DQS_DN<6>
  \dqs6_b_t||tdqs6_b_t\  = M_A_CPU0_SB_DQS_DP<6>
  VSS114  = GND
  DQ14_B  = M_A_CPU0_SB_DQ<14>
  VSS115  = GND
  DQ15_B  = M_A_CPU0_SB_DQ<15>
  VSS116  = GND
  DQ18_B  = M_A_CPU0_SB_DQ<18>
  VSS117  = GND
  DQ19_B  = M_A_CPU0_SB_DQ<19>
  VSS118  = GND
  \dqs7_b_c||tdqs7_b_c\  = M_A_CPU0_SB_DQS_DN<7>
  \dqs7_b_t||tdqs7_b_t\  = M_A_CPU0_SB_DQS_DP<7>
  VSS119  = GND
  DQ22_B  = M_A_CPU0_SB_DQ<22>
  VSS120  = GND
  DQ23_B  = M_A_CPU0_SB_DQ<23>
  VSS121  = GND
  DQ26_B  = M_A_CPU0_SB_DQ<26>
  VSS122  = GND
  DQ27_B  = M_A_CPU0_SB_DQ<27>
  VSS123  = GND
  \dqs8_b_c||tdqs8_b_c\  = M_A_CPU0_SB_DQS_DN<8>
  \dqs8_b_t||tdqs8_b_t\  = M_A_CPU0_SB_DQS_DP<8>
  VSS124  = GND
  DQ30_B  = M_A_CPU0_SB_DQ<30>
  VSS125  = GND
  DQ31_B  = M_A_CPU0_SB_DQ<31>
  VSS126  = GND
  G1  = GND
  G2  = GND
  G3  = GND

(kicad_pcb
	(version 20260206)
	(generator "pcbnew")
	(generator_version "10.0")
	(general
		(thickness 1.6)
		(legacy_teardrops no)
	)
	(paper "A4")
	(title_block
		(title "03242023_DA0F0TMBIJ0_F0T_Motherboard_J_brd_V01_OCP.brd")
		(comment 1 "Grand Teton / footprint 1236 of 6105 (J1), pads 46-91 of 291")
	)
	(layers
		(0 "F.Cu" signal "TOP")
		(4 "In1.Cu" signal "GND")
		(6 "In2.Cu" signal "IN1")
		(8 "In3.Cu" signal "GND1")
		(10 "In4.Cu" signal "IN2")
		(12 "In5.Cu" signal "GND2")
		(14 "In6.Cu" signal "IN3")
		(16 "In7.Cu" signal "GND3")
		(18 "In8.Cu" signal "VCC")
		(20 "In9.Cu" signal "VCC1")
		(22 "In10.Cu" signal "GND4")
		(24 "In11.Cu" signal "IN4")
		(26 "In12.Cu" signal "GND5")
		(28 "In13.Cu" signal "IN5")
		(30 "In14.Cu" signal "GND6")
		(32 "In15.Cu" signal "IN6")
		(34 "In16.Cu" signal "GND7")
		(2 "B.Cu" signal "BOTTOM")
		(9 "F.Adhes" user "F.Adhesive")
		(11 "B.Adhes" user "B.Adhesive")
		(13 "F.Paste" user "Package Geometry/Pastemask Top")
		(15 "B.Paste" user "Package Geometry/Pastemask Bottom")
		(5 "F.SilkS" user "Ref Des/Silkscreen Top")
		(7 "B.SilkS" user "Ref Des/Silkscreen Bottom")
		(1 "F.Mask" user "Board Geometry/Soldermask Top")
		(3 "B.Mask" user "Board Geometry/Soldermask Bottom")
		(17 "Dwgs.User" user "User.Drawings")
		(19 "Cmts.User" user "User.Comments")
		(21 "Eco1.User" user "User.Eco1")
		(23 "Eco2.User" user "User.Eco2")
		(25 "Edge.Cuts" user "Board Geometry/Outline")
		(27 "Margin" user)
		(31 "F.CrtYd" user "Package Geometry/Place Bound Top")
		(29 "B.CrtYd" user "Package Geometry/Place Bound Bottom")
		(35 "F.Fab" user "Ref Des/Assembly Top")
		(33 "B.Fab" user "Ref Des/Assembly Bottom")
	)
	(footprint ""
		(layer "F.Cu")
		(at 303.393348 -258.091686)
		(property "Reference" "J1"
			(at -3.683 -81.702148 0)
			(unlocked yes)
			(layer "F.SilkS")
			(effects
				(font
					(size 0.7874 0.5842)
					(thickness 0.1524)
				)
				(justify left)
			)
		)
		(property "Value" ""
			(at 0 0 0)
			(layer "F.Fab")
			(effects
				(font
					(size 1.27 1.27)
				)
			)
		)
		(duplicate_pad_numbers_are_jumpers no)
		(pad "46" smd rect
			(at -2.050034 -25.07488 270)
			(size 0.519938 1.4986)
			(layers "F.Cu" "F.Mask" "F.Paste")
			(net "GND")
		)
		(pad "47" smd rect
			(at -2.050034 -24.224996 270)
			(size 0.519938 1.4986)
			(layers "F.Cu" "F.Mask" "F.Paste")
			(net "M_A_CPU0_SA_DQ<28>")
		)
		(pad "48" smd rect
			(at -2.050034 -23.375112 270)
			(size 0.519938 1.4986)
			(layers "F.Cu" "F.Mask" "F.Paste")
			(net "GND")
		)
		(pad "49" smd rect
			(at -2.050034 -22.524974 270)
			(size 0.519938 1.4986)
			(layers "F.Cu" "F.Mask" "F.Paste")
			(net "M_A_CPU0_SA_DQ<29>")
		)
		(pad "50" smd rect
			(at -2.050034 -21.67509 270)
			(size 0.519938 1.4986)
			(layers "F.Cu" "F.Mask" "F.Paste")
			(net "GND")
		)
		(pad "51" smd rect
			(at -2.050034 -20.824952 270)
			(size 0.519938 1.4986)
			(layers "F.Cu" "F.Mask" "F.Paste")
			(net "M_A_CPU0_SA_CB<0>")
		)
		(pad "52" smd rect
			(at -2.050034 -19.975068 270)
			(size 0.519938 1.4986)
			(layers "F.Cu" "F.Mask" "F.Paste")
			(net "GND")
		)
		(pad "53" smd rect
			(at -2.050034 -19.12493 270)
			(size 0.519938 1.4986)
			(layers "F.Cu" "F.Mask" "F.Paste")
			(net "M_A_CPU0_SA_CB<1>")
		)
		(pad "54" smd rect
			(at -2.050034 -18.275046 270)
			(size 0.519938 1.4986)
			(layers "F.Cu" "F.Mask" "F.Paste")
			(net "GND")
		)
		(pad "55" smd rect
			(at -2.050034 -17.424908 270)
			(size 0.519938 1.4986)
			(layers "F.Cu" "F.Mask" "F.Paste")
			(net "M_A_CPU0_SA_DQS_DP<4>")
		)
		(pad "56" smd rect
			(at -2.050034 -16.575024 270)
			(size 0.519938 1.4986)
			(layers "F.Cu" "F.Mask" "F.Paste")
			(net "M_A_CPU0_SA_DQS_DN<4>")
		)
		(pad "57" smd rect
			(at -2.050034 -15.724886 270)
			(size 0.519938 1.4986)
			(layers "F.Cu" "F.Mask" "F.Paste")
			(net "GND")
		)
		(pad "58" smd rect
			(at -2.050034 -14.875002 270)
			(size 0.519938 1.4986)
			(layers "F.Cu" "F.Mask" "F.Paste")
			(net "M_A_CPU0_SA_CB<4>")
		)
		(pad "59" smd rect
			(at -2.050034 -14.025118 270)
			(size 0.519938 1.4986)
			(layers "F.Cu" "F.Mask" "F.Paste")
			(net "GND")
		)
		(pad "60" smd rect
			(at -2.050034 -13.17498 270)
			(size 0.519938 1.4986)
			(layers "F.Cu" "F.Mask" "F.Paste")
			(net "M_A_CPU0_SA_CB<5>")
		)
		(pad "61" smd rect
			(at -2.050034 -12.325096 270)
			(size 0.519938 1.4986)
			(layers "F.Cu" "F.Mask" "F.Paste")
			(net "GND")
		)
		(pad "62" smd rect
			(at -2.050034 -11.474958 270)
			(size 0.519938 1.4986)
			(layers "F.Cu" "F.Mask" "F.Paste")
			(net "M_A_CPU0_ALERT_N")
		)
		(pad "63" smd rect
			(at -2.050034 -10.625074 270)
			(size 0.519938 1.4986)
			(layers "F.Cu" "F.Mask" "F.Paste")
			(net "GND")
		)
		(pad "64" smd rect
			(at -2.050034 -9.774936 270)
			(size 0.519938 1.4986)
			(layers "F.Cu" "F.Mask" "F.Paste")
			(net "M_A_CPU0_SA_CS_N<0>")
		)
		(pad "65" smd rect
			(at -2.050034 -8.925052 270)
			(size 0.519938 1.4986)
			(layers "F.Cu" "F.Mask" "F.Paste")
			(net "GND")
		)
		(pad "66" smd rect
			(at -2.050034 -8.074914 270)
			(size 0.519938 1.4986)
			(layers "F.Cu" "F.Mask" "F.Paste")
			(net "M_A_CPU0_SA_CA<0>")
		)
		(pad "67" smd rect
			(at -2.050034 -7.22503 270)
			(size 0.519938 1.4986)
			(layers "F.Cu" "F.Mask" "F.Paste")
			(net "GND")
		)
		(pad "68" smd rect
			(at -2.050034 -6.374892 270)
			(size 0.519938 1.4986)
			(layers "F.Cu" "F.Mask" "F.Paste")
			(net "M_A_CPU0_SA_CA<2>")
		)
		(pad "69" smd rect
			(at -2.050034 -5.525008 270)
			(size 0.519938 1.4986)
			(layers "F.Cu" "F.Mask" "F.Paste")
			(net "GND")
		)
		(pad "70" smd rect
			(at -2.050034 -4.675124 270)
			(size 0.519938 1.4986)
			(layers "F.Cu" "F.Mask" "F.Paste")
			(net "M_A_CPU0_SA_CA<4>")
		)
		(pad "71" smd rect
			(at -2.050034 -3.824986 270)
			(size 0.519938 1.4986)
			(layers "F.Cu" "F.Mask" "F.Paste")
			(net "GND")
		)
		(pad "72" smd rect
			(at -2.050034 -2.975102 270)
			(size 0.519938 1.4986)
			(layers "F.Cu" "F.Mask" "F.Paste")
			(net "M_A_CPU0_SA_CA<6>")
		)
		(pad "73" smd rect
			(at -2.050034 -2.124964 270)
			(size 0.519938 1.4986)
			(layers "F.Cu" "F.Mask" "F.Paste")
			(net "GND")
		)
		(pad "74" smd rect
			(at -2.050034 -1.27508 270)
			(size 0.519938 1.4986)
			(layers "F.Cu" "F.Mask" "F.Paste")
			(net "M_A_CPU0_SA_PAR")
		)
		(pad "75" smd rect
			(at -2.050034 -0.424942 270)
			(size 0.519938 1.4986)
			(layers "F.Cu" "F.Mask" "F.Paste")
			(net "GND")
		)
		(pad "76" smd rect
			(at -2.050034 5.525008 270)
			(size 0.519938 1.4986)
			(layers "F.Cu" "F.Mask" "F.Paste")
			(net "M_A_CPU0_SB_CA<0>")
		)
		(pad "77" smd rect
			(at -2.050034 6.374892 270)
			(size 0.519938 1.4986)
			(layers "F.Cu" "F.Mask" "F.Paste")
			(net "GND")
		)
		(pad "78" smd rect
			(at -2.050034 7.22503 270)
			(size 0.519938 1.4986)
			(layers "F.Cu" "F.Mask" "F.Paste")
			(net "M_A_CPU0_SB_CA<2>")
		)
		(pad "79" smd rect
			(at -2.050034 8.074914 270)
			(size 0.519938 1.4986)
			(layers "F.Cu" "F.Mask" "F.Paste")
			(net "GND")
		)
		(pad "80" smd rect
			(at -2.050034 8.925052 270)
			(size 0.519938 1.4986)
			(layers "F.Cu" "F.Mask" "F.Paste")
			(net "M_A_CPU0_SB_CA<4>")
		)
		(pad "81" smd rect
			(at -2.050034 9.774936 270)
			(size 0.519938 1.4986)
			(layers "F.Cu" "F.Mask" "F.Paste")
			(net "GND")
		)
		(pad "82" smd rect
			(at -2.050034 10.625074 270)
			(size 0.519938 1.4986)
			(layers "F.Cu" "F.Mask" "F.Paste")
			(net "M_A_CPU0_SB_CA<6>")
		)
		(pad "83" smd rect
			(at -2.050034 11.474958 270)
			(size 0.519938 1.4986)
			(layers "F.Cu" "F.Mask" "F.Paste")
			(net "GND")
		)
		(pad "84" smd rect
			(at -2.050034 12.325096 270)
			(size 0.519938 1.4986)
			(layers "F.Cu" "F.Mask" "F.Paste")
			(net "M_A_CPU0_SB_CS_N<0>")
		)
		(pad "85" smd rect
			(at -2.050034 13.17498 270)
			(size 0.519938 1.4986)
			(layers "F.Cu" "F.Mask" "F.Paste")
			(net "GND")
		)
		(pad "86" smd rect
			(at -2.050034 14.025118 270)
			(size 0.519938 1.4986)
			(layers "F.Cu" "F.Mask" "F.Paste")
			(net "M_A_CPU0_SA_RSP<0>")
		)
		(pad "87" smd rect
			(at -2.050034 14.875002 270)
			(size 0.519938 1.4986)
			(layers "F.Cu" "F.Mask" "F.Paste")
			(net "M_A_CPU0_SB_RSP<0>")
		)
		(pad "88" smd rect
			(at -2.050034 15.724886 270)
			(size 0.519938 1.4986)
			(layers "F.Cu" "F.Mask" "F.Paste")
			(net "GND")
		)
		(pad "89" smd rect
			(at -2.050034 16.575024 270)
			(size 0.519938 1.4986)
			(layers "F.Cu" "F.Mask" "F.Paste")
			(net "M_A_CPU0_SB_CB<4>")
		)
		(pad "90" smd rect
			(at -2.050034 17.424908 270)
			(size 0.519938 1.4986)
			(layers "F.Cu" "F.Mask" "F.Paste")
			(net "GND")
		)
		(pad "91" smd rect
			(at -2.050034 18.275046 270)
			(size 0.519938 1.4986)
			(layers "F.Cu" "F.Mask" "F.Paste")
			(net "M_A_CPU0_SB_CB<5>")
		)
	)
)
